(kicad_pcb
	(version 20260206)
	(generator "pcbnew")
	(generator_version "10.0")
	(general
		(thickness 1.6)
		(legacy_teardrops no)
	)
	(paper "A4")
	(title_block
		(title "03242023_DA0F0TMBIJ0_F0T_Motherboard_J_brd_V01_OCP.brd")
		(comment 1 "Grand Teton / footprint 3039 of 6105 (U2), pads 3134-3244 of 4677")
	)
	(layers
		(0 "F.Cu" signal "TOP")
		(4 "In1.Cu" signal "GND")
		(6 "In2.Cu" signal "IN1")
		(8 "In3.Cu" signal "GND1")
		(10 "In4.Cu" signal "IN2")
		(12 "In5.Cu" signal "GND2")
		(14 "In6.Cu" signal "IN3")
		(16 "In7.Cu" signal "GND3")
		(18 "In8.Cu" signal "VCC")
		(20 "In9.Cu" signal "VCC1")
		(22 "In10.Cu" signal "GND4")
		(24 "In11.Cu" signal "IN4")
		(26 "In12.Cu" signal "GND5")
		(28 "In13.Cu" signal "IN5")
		(30 "In14.Cu" signal "GND6")
		(32 "In15.Cu" signal "IN6")
		(34 "In16.Cu" signal "GND7")
		(2 "B.Cu" signal "BOTTOM")
		(9 "F.Adhes" user "F.Adhesive")
		(11 "B.Adhes" user "B.Adhesive")
		(13 "F.Paste" user "Package Geometry/Pastemask Top")
		(15 "B.Paste" user "Package Geometry/Pastemask Bottom")
		(5 "F.SilkS" user "Ref Des/Silkscreen Top")
		(7 "B.SilkS" user "Ref Des/Silkscreen Bottom")
		(1 "F.Mask" user "Board Geometry/Soldermask Top")
		(3 "B.Mask" user "Board Geometry/Soldermask Bottom")
		(17 "Dwgs.User" user "User.Drawings")
		(19 "Cmts.User" user "User.Comments")
		(21 "Eco1.User" user "User.Eco1")
		(23 "Eco2.User" user "User.Eco2")
		(25 "Edge.Cuts" user "Board Geometry/Outline")
		(27 "Margin" user)
		(31 "F.CrtYd" user "Package Geometry/Place Bound Top")
		(29 "B.CrtYd" user "Package Geometry/Place Bound Bottom")
		(35 "F.Fab" user "Ref Des/Assembly Top")
		(33 "B.Fab" user "Ref Des/Assembly Bottom")
	)
	(footprint ""
		(layer "F.Cu")
		(at 359.870248 -251.76988 90)
		(property "Reference" "U2"
			(at -74.416158 -44.488608 0)
			(unlocked yes)
			(layer "F.SilkS")
			(effects
				(font
					(size 1.6002 1.1938)
					(thickness 0.1524)
				)
				(justify left)
			)
		)
		(property "Value" ""
			(at 0 0 90)
			(layer "F.Fab")
			(effects
				(font
					(size 1.27 1.27)
				)
			)
		)
		(duplicate_pad_numbers_are_jumpers no)
		(pad "DU48" smd circle
			(at 2.427732 18.146268 270)
			(size 0.4318 0.4318)
			(layers "F.Cu" "F.Mask" "F.Paste")
			(net "M_G_CPU0_SB_RSP<0>")
		)
		(pad "DU50" smd circle
			(at 4.055618 18.146268 270)
			(size 0.4318 0.4318)
			(layers "F.Cu" "F.Mask" "F.Paste")
			(net "M_F_CPU0_SB_CA<1>")
		)
		(pad "DU52" smd circle
			(at 5.68325 18.146268 270)
			(size 0.4318 0.4318)
			(layers "F.Cu" "F.Mask" "F.Paste")
			(net "GND")
		)
		(pad "DU54" smd circle
			(at 7.311136 18.146268 270)
			(size 0.4318 0.4318)
			(layers "F.Cu" "F.Mask" "F.Paste")
			(net "M_F_CPU0_SA_DQ<28>")
		)
		(pad "DU56" smd circle
			(at 8.939022 18.146268 270)
			(size 0.4318 0.4318)
			(layers "F.Cu" "F.Mask" "F.Paste")
			(net "M_F_CPU0_SA_DQ<25>")
		)
		(pad "DU58" smd circle
			(at 10.566654 18.146268 270)
			(size 0.4318 0.4318)
			(layers "F.Cu" "F.Mask" "F.Paste")
			(net "GND")
		)
		(pad "DU60" smd circle
			(at 12.19454 18.146268 270)
			(size 0.4318 0.4318)
			(layers "F.Cu" "F.Mask" "F.Paste")
			(net "M_G_CPU0_SA_DQ<20>")
		)
		(pad "DU62" smd circle
			(at 13.822426 18.146268 270)
			(size 0.4318 0.4318)
			(layers "F.Cu" "F.Mask" "F.Paste")
			(net "M_G_CPU0_SA_DQ<17>")
		)
		(pad "DU64" smd circle
			(at 15.450058 18.146268 270)
			(size 0.4318 0.4318)
			(layers "F.Cu" "F.Mask" "F.Paste")
			(net "GND")
		)
		(pad "DU66" smd circle
			(at 17.07769 18.146268 270)
			(size 0.4318 0.4318)
			(layers "F.Cu" "F.Mask" "F.Paste")
			(net "M_F_CPU0_SA_DQ<12>")
		)
		(pad "DU68" smd circle
			(at 18.705576 18.146268 270)
			(size 0.4318 0.4318)
			(layers "F.Cu" "F.Mask" "F.Paste")
			(net "M_F_CPU0_SA_DQ<9>")
		)
		(pad "DU70" smd circle
			(at 20.333462 18.146268 270)
			(size 0.4318 0.4318)
			(layers "F.Cu" "F.Mask" "F.Paste")
			(net "GND")
		)
		(pad "DU72" smd circle
			(at 21.961094 18.146268 270)
			(size 0.4318 0.4318)
			(layers "F.Cu" "F.Mask" "F.Paste")
			(net "M_G_CPU0_SA_DQ<4>")
		)
		(pad "DU74" smd circle
			(at 23.58898 18.146268 270)
			(size 0.4318 0.4318)
			(layers "F.Cu" "F.Mask" "F.Paste")
			(net "M_G_CPU0_SA_DQ<1>")
		)
		(pad "DU76" smd circle
			(at 25.216612 18.146268 270)
			(size 0.4318 0.4318)
			(layers "F.Cu" "F.Mask" "F.Paste")
			(net "GND")
		)
		(pad "DU78" smd circle
			(at 26.844498 18.146268 270)
			(size 0.4318 0.4318)
			(layers "F.Cu" "F.Mask" "F.Paste")
			(net "GND")
		)
		(pad "DU80" smd circle
			(at 28.472384 18.146268 270)
			(size 0.4318 0.4318)
			(layers "F.Cu" "F.Mask" "F.Paste")
			(net "Net_681")
		)
		(pad "DU82" smd circle
			(at 30.100016 18.146268 270)
			(size 0.4318 0.4318)
			(layers "F.Cu" "F.Mask" "F.Paste")
			(net "Net_656")
		)
		(pad "DU84" smd circle
			(at 31.727902 18.146268 270)
			(size 0.4318 0.4318)
			(layers "F.Cu" "F.Mask" "F.Paste")
			(net "GND")
		)
		(pad "DU86" smd circle
			(at 33.355534 18.146268 270)
			(size 0.4318 0.4318)
			(layers "F.Cu" "F.Mask" "F.Paste")
			(net "P5E_CPU0_PE3_TX_DP<4>")
		)
		(pad "DU88" smd circle
			(at 34.98342 18.146268 270)
			(size 0.4318 0.4318)
			(layers "F.Cu" "F.Mask" "F.Paste")
			(net "GND")
		)
		(pad "DU90" smd circle
			(at 36.611306 18.146268 270)
			(size 0.4318 0.4318)
			(layers "F.Cu" "F.Mask" "F.Paste")
			(net "P5E_CPU0_PE3_RX_DN<5>")
		)
		(pad "DV2" smd circle
			(at -36.611306 18.505932 270)
			(size 0.4318 0.4318)
			(layers "F.Cu" "F.Mask" "F.Paste")
			(net "UPI_CPU1_CPU0_P0P1_DP<5>")
		)
		(pad "DV4" smd circle
			(at -34.98342 18.505932 270)
			(size 0.4318 0.4318)
			(layers "F.Cu" "F.Mask" "F.Paste")
			(net "GND")
		)
		(pad "DV6" smd circle
			(at -33.355534 18.505932 270)
			(size 0.4318 0.4318)
			(layers "F.Cu" "F.Mask" "F.Paste")
			(net "UPI_CPU0_CPU1_P1P0_DN<4>")
		)
		(pad "DV8" smd circle
			(at -31.727902 18.505932 270)
			(size 0.4318 0.4318)
			(layers "F.Cu" "F.Mask" "F.Paste")
			(net "GND")
		)
		(pad "DV10" smd circle
			(at -30.100016 18.505932 270)
			(size 0.4318 0.4318)
			(layers "F.Cu" "F.Mask" "F.Paste")
			(net "P5E_CPU0_PE2_RX_DP<10>")
		)
		(pad "DV12" smd circle
			(at -28.472384 18.505932 270)
			(size 0.4318 0.4318)
			(layers "F.Cu" "F.Mask" "F.Paste")
			(net "GND")
		)
		(pad "DV14" smd circle
			(at -26.844498 18.505932 270)
			(size 0.4318 0.4318)
			(layers "F.Cu" "F.Mask" "F.Paste")
			(net "P5E_CPU0_PE2_TX_DN<11>")
		)
		(pad "DV16" smd circle
			(at -25.216612 18.505932 270)
			(size 0.4318 0.4318)
			(layers "F.Cu" "F.Mask" "F.Paste")
			(net "GND")
		)
		(pad "DV18" smd circle
			(at -23.58898 18.505932 270)
			(size 0.4318 0.4318)
			(layers "F.Cu" "F.Mask" "F.Paste")
			(net "M_F_CPU0_SB_DQS_DP<3>")
		)
		(pad "DV20" smd circle
			(at -21.961094 18.505932 270)
			(size 0.4318 0.4318)
			(layers "F.Cu" "F.Mask" "F.Paste")
			(net "M_F_CPU0_SB_DQ<24>")
		)
		(pad "DV22" smd circle
			(at -20.333462 18.505932 270)
			(size 0.4318 0.4318)
			(layers "F.Cu" "F.Mask" "F.Paste")
			(net "M_G_CPU0_SB_DQ<21>")
		)
		(pad "DV24" smd circle
			(at -18.705576 18.505932 270)
			(size 0.4318 0.4318)
			(layers "F.Cu" "F.Mask" "F.Paste")
			(net "M_G_CPU0_SB_DQS_DN<2>")
		)
		(pad "DV26" smd circle
			(at -17.07769 18.505932 270)
			(size 0.4318 0.4318)
			(layers "F.Cu" "F.Mask" "F.Paste")
			(net "M_G_CPU0_SB_DQ<16>")
		)
		(pad "DV28" smd circle
			(at -15.450058 18.505932 270)
			(size 0.4318 0.4318)
			(layers "F.Cu" "F.Mask" "F.Paste")
			(net "M_F_CPU0_SB_DQ<5>")
		)
		(pad "DV30" smd circle
			(at -13.822426 18.505932 270)
			(size 0.4318 0.4318)
			(layers "F.Cu" "F.Mask" "F.Paste")
			(net "M_F_CPU0_SB_DQS_DN<0>")
		)
		(pad "DV32" smd circle
			(at -12.19454 18.505932 270)
			(size 0.4318 0.4318)
			(layers "F.Cu" "F.Mask" "F.Paste")
			(net "M_F_CPU0_SB_DQ<0>")
		)
		(pad "DV34" smd circle
			(at -10.566654 18.505932 270)
			(size 0.4318 0.4318)
			(layers "F.Cu" "F.Mask" "F.Paste")
			(net "M_G_CPU0_SB_CB<1>")
		)
		(pad "DV36" smd circle
			(at -8.939022 18.505932 270)
			(size 0.4318 0.4318)
			(layers "F.Cu" "F.Mask" "F.Paste")
			(net "M_G_CPU0_SB_DQS_DN<9>")
		)
		(pad "DV38" smd circle
			(at -7.311136 18.505932 270)
			(size 0.4318 0.4318)
			(layers "F.Cu" "F.Mask" "F.Paste")
			(net "M_G_CPU0_SB_CB<4>")
		)
		(pad "DV40" smd circle
			(at -5.68325 18.505932 270)
			(size 0.4318 0.4318)
			(layers "F.Cu" "F.Mask" "F.Paste")
			(net "M_G_CPU0_SB_CS_N<3>")
		)
		(pad "DV42" smd circle
			(at -4.055618 18.505932 270)
			(size 0.4318 0.4318)
			(layers "F.Cu" "F.Mask" "F.Paste")
			(net "GND")
		)
		(pad "DV44" smd circle
			(at -2.427732 18.505932 270)
			(size 0.4318 0.4318)
			(layers "F.Cu" "F.Mask" "F.Paste")
			(net "M_G_CPU0_SB_CA<2>")
		)
		(pad "DV47" smd circle
			(at 1.613916 18.615914 270)
			(size 0.4318 0.4318)
			(layers "F.Cu" "F.Mask" "F.Paste")
			(net "M_G_CPU0_SB_RSP<1>")
		)
		(pad "DV49" smd circle
			(at 3.241802 18.615914 270)
			(size 0.4318 0.4318)
			(layers "F.Cu" "F.Mask" "F.Paste")
			(net "M_F_CPU0_CLK_DN<1>")
		)
		(pad "DV51" smd circle
			(at 4.869434 18.615914 270)
			(size 0.4318 0.4318)
			(layers "F.Cu" "F.Mask" "F.Paste")
			(net "M_F_CPU0_SB_CA<0>")
		)
		(pad "DV53" smd circle
			(at 6.49732 18.615914 270)
			(size 0.4318 0.4318)
			(layers "F.Cu" "F.Mask" "F.Paste")
			(net "M_F_CPU0_SA_DQ<29>")
		)
		(pad "DV55" smd circle
			(at 8.124952 18.615914 270)
			(size 0.4318 0.4318)
			(layers "F.Cu" "F.Mask" "F.Paste")
			(net "M_F_CPU0_SA_DQS_DN<3>")
		)
		(pad "DV57" smd circle
			(at 9.752838 18.615914 270)
			(size 0.4318 0.4318)
			(layers "F.Cu" "F.Mask" "F.Paste")
			(net "M_F_CPU0_SA_DQ<24>")
		)
		(pad "DV59" smd circle
			(at 11.380724 18.615914 270)
			(size 0.4318 0.4318)
			(layers "F.Cu" "F.Mask" "F.Paste")
			(net "M_G_CPU0_SA_DQ<21>")
		)
		(pad "DV61" smd circle
			(at 13.008356 18.615914 270)
			(size 0.4318 0.4318)
			(layers "F.Cu" "F.Mask" "F.Paste")
			(net "M_G_CPU0_SA_DQS_DP<2>")
		)
		(pad "DV63" smd circle
			(at 14.635988 18.615914 270)
			(size 0.4318 0.4318)
			(layers "F.Cu" "F.Mask" "F.Paste")
			(net "M_G_CPU0_SA_DQ<16>")
		)
		(pad "DV65" smd circle
			(at 16.263874 18.615914 270)
			(size 0.4318 0.4318)
			(layers "F.Cu" "F.Mask" "F.Paste")
			(net "M_F_CPU0_SA_DQ<13>")
		)
		(pad "DV67" smd circle
			(at 17.89176 18.615914 270)
			(size 0.4318 0.4318)
			(layers "F.Cu" "F.Mask" "F.Paste")
			(net "M_F_CPU0_SA_DQS_DP<1>")
		)
		(pad "DV69" smd circle
			(at 19.519392 18.615914 270)
			(size 0.4318 0.4318)
			(layers "F.Cu" "F.Mask" "F.Paste")
			(net "M_F_CPU0_SA_DQ<8>")
		)
		(pad "DV71" smd circle
			(at 21.147278 18.615914 270)
			(size 0.4318 0.4318)
			(layers "F.Cu" "F.Mask" "F.Paste")
			(net "M_G_CPU0_SA_DQ<5>")
		)
		(pad "DV73" smd circle
			(at 22.77491 18.615914 270)
			(size 0.4318 0.4318)
			(layers "F.Cu" "F.Mask" "F.Paste")
			(net "M_G_CPU0_SA_DQS_DN<0>")
		)
		(pad "DV75" smd circle
			(at 24.402796 18.615914 270)
			(size 0.4318 0.4318)
			(layers "F.Cu" "F.Mask" "F.Paste")
			(net "M_G_CPU0_SA_DQ<0>")
		)
		(pad "DV77" smd circle
			(at 26.030682 18.615914 270)
			(size 0.4318 0.4318)
			(layers "F.Cu" "F.Mask" "F.Paste")
			(net "GND")
		)
		(pad "DV79" smd circle
			(at 27.658314 18.615914 270)
			(size 0.4318 0.4318)
			(layers "F.Cu" "F.Mask" "F.Paste")
			(net "GND")
		)
		(pad "DV81" smd circle
			(at 29.2862 18.615914 270)
			(size 0.4318 0.4318)
			(layers "F.Cu" "F.Mask" "F.Paste")
			(net "GND")
		)
		(pad "DV83" smd circle
			(at 30.914086 18.615914 270)
			(size 0.4318 0.4318)
			(layers "F.Cu" "F.Mask" "F.Paste")
			(net "GND")
		)
		(pad "DV85" smd circle
			(at 32.541718 18.615914 270)
			(size 0.4318 0.4318)
			(layers "F.Cu" "F.Mask" "F.Paste")
			(net "P5E_CPU0_PE3_TX_DN<3>")
		)
		(pad "DV87" smd circle
			(at 34.169604 18.615914 270)
			(size 0.4318 0.4318)
			(layers "F.Cu" "F.Mask" "F.Paste")
			(net "GND")
		)
		(pad "DV89" smd circle
			(at 35.797236 18.615914 270)
			(size 0.4318 0.4318)
			(layers "F.Cu" "F.Mask" "F.Paste")
			(net "P5E_CPU0_PE3_RX_DN<4>")
		)
		(pad "DV91" smd oval
			(at 37.425122 18.615914)
			(size 0.381 0.4826)
			(drill
				(offset 0 -0.0508)
			)
			(layers "F.Cu" "F.Mask" "F.Paste")
			(net "GND")
		)
		(pad "DW1" smd oval
			(at -37.425122 18.976086 180)
			(size 0.381 0.4826)
			(drill
				(offset 0 -0.0508)
			)
			(layers "F.Cu" "F.Mask" "F.Paste")
			(net "GND")
		)
		(pad "DW3" smd circle
			(at -35.797236 18.976086 270)
			(size 0.4318 0.4318)
			(layers "F.Cu" "F.Mask" "F.Paste")
			(net "UPI_CPU1_CPU0_P0P1_DP<4>")
		)
		(pad "DW5" smd circle
			(at -34.169604 18.976086 270)
			(size 0.4318 0.4318)
			(layers "F.Cu" "F.Mask" "F.Paste")
			(net "GND")
		)
		(pad "DW7" smd circle
			(at -32.541718 18.976086 270)
			(size 0.4318 0.4318)
			(layers "F.Cu" "F.Mask" "F.Paste")
			(net "UPI_CPU0_CPU1_P1P0_DN<3>")
		)
		(pad "DW9" smd circle
			(at -30.914086 18.976086 270)
			(size 0.4318 0.4318)
			(layers "F.Cu" "F.Mask" "F.Paste")
			(net "GND")
		)
		(pad "DW11" smd circle
			(at -29.2862 18.976086 270)
			(size 0.4318 0.4318)
			(layers "F.Cu" "F.Mask" "F.Paste")
			(net "P5E_CPU0_PE2_RX_DP<11>")
		)
		(pad "DW13" smd circle
			(at -27.658314 18.976086 270)
			(size 0.4318 0.4318)
			(layers "F.Cu" "F.Mask" "F.Paste")
			(net "GND")
		)
		(pad "DW15" smd circle
			(at -26.030682 18.976086 270)
			(size 0.4318 0.4318)
			(layers "F.Cu" "F.Mask" "F.Paste")
			(net "P5E_CPU0_PE2_TX_DP<11>")
		)
		(pad "DW17" smd circle
			(at -24.402796 18.976086 270)
			(size 0.4318 0.4318)
			(layers "F.Cu" "F.Mask" "F.Paste")
			(net "GND")
		)
		(pad "DW19" smd circle
			(at -22.77491 18.976086 270)
			(size 0.4318 0.4318)
			(layers "F.Cu" "F.Mask" "F.Paste")
			(net "GND")
		)
		(pad "DW21" smd circle
			(at -21.147278 18.976086 270)
			(size 0.4318 0.4318)
			(layers "F.Cu" "F.Mask" "F.Paste")
			(net "GND")
		)
		(pad "DW23" smd circle
			(at -19.519392 18.976086 270)
			(size 0.4318 0.4318)
			(layers "F.Cu" "F.Mask" "F.Paste")
			(net "GND")
		)
		(pad "DW25" smd circle
			(at -17.89176 18.976086 270)
			(size 0.4318 0.4318)
			(layers "F.Cu" "F.Mask" "F.Paste")
			(net "GND")
		)
		(pad "DW27" smd circle
			(at -16.263874 18.976086 270)
			(size 0.4318 0.4318)
			(layers "F.Cu" "F.Mask" "F.Paste")
			(net "GND")
		)
		(pad "DW29" smd circle
			(at -14.635988 18.976086 270)
			(size 0.4318 0.4318)
			(layers "F.Cu" "F.Mask" "F.Paste")
			(net "GND")
		)
		(pad "DW31" smd circle
			(at -13.008356 18.976086 270)
			(size 0.4318 0.4318)
			(layers "F.Cu" "F.Mask" "F.Paste")
			(net "GND")
		)
		(pad "DW33" smd circle
			(at -11.380724 18.976086 270)
			(size 0.4318 0.4318)
			(layers "F.Cu" "F.Mask" "F.Paste")
			(net "GND")
		)
		(pad "DW35" smd circle
			(at -9.752838 18.976086 270)
			(size 0.4318 0.4318)
			(layers "F.Cu" "F.Mask" "F.Paste")
			(net "GND")
		)
		(pad "DW37" smd circle
			(at -8.124952 18.976086 270)
			(size 0.4318 0.4318)
			(layers "F.Cu" "F.Mask" "F.Paste")
			(net "GND")
		)
		(pad "DW39" smd circle
			(at -6.49732 18.976086 270)
			(size 0.4318 0.4318)
			(layers "F.Cu" "F.Mask" "F.Paste")
			(net "GND")
		)
		(pad "DW41" smd circle
			(at -4.869434 18.976086 270)
			(size 0.4318 0.4318)
			(layers "F.Cu" "F.Mask" "F.Paste")
			(net "GND")
		)
		(pad "DW43" smd circle
			(at -3.241802 18.976086 270)
			(size 0.4318 0.4318)
			(layers "F.Cu" "F.Mask" "F.Paste")
			(net "GND")
		)
		(pad "DW45" smd circle
			(at -1.613916 18.976086 270)
			(size 0.4318 0.4318)
			(layers "F.Cu" "F.Mask" "F.Paste")
			(net "GND")
		)
		(pad "DW48" smd circle
			(at 2.427732 19.086068 270)
			(size 0.4318 0.4318)
			(layers "F.Cu" "F.Mask" "F.Paste")
			(net "GND")
		)
		(pad "DW50" smd circle
			(at 4.055618 19.086068 270)
			(size 0.4318 0.4318)
			(layers "F.Cu" "F.Mask" "F.Paste")
			(net "GND")
		)
		(pad "DW52" smd circle
			(at 5.68325 19.086068 270)
			(size 0.4318 0.4318)
			(layers "F.Cu" "F.Mask" "F.Paste")
			(net "GND")
		)
		(pad "DW54" smd circle
			(at 7.311136 19.086068 270)
			(size 0.4318 0.4318)
			(layers "F.Cu" "F.Mask" "F.Paste")
			(net "GND")
		)
		(pad "DW56" smd circle
			(at 8.939022 19.086068 270)
			(size 0.4318 0.4318)
			(layers "F.Cu" "F.Mask" "F.Paste")
			(net "GND")
		)
		(pad "DW58" smd circle
			(at 10.566654 19.086068 270)
			(size 0.4318 0.4318)
			(layers "F.Cu" "F.Mask" "F.Paste")
			(net "GND")
		)
		(pad "DW60" smd circle
			(at 12.19454 19.086068 270)
			(size 0.4318 0.4318)
			(layers "F.Cu" "F.Mask" "F.Paste")
			(net "GND")
		)
		(pad "DW62" smd circle
			(at 13.822426 19.086068 270)
			(size 0.4318 0.4318)
			(layers "F.Cu" "F.Mask" "F.Paste")
			(net "GND")
		)
		(pad "DW64" smd circle
			(at 15.450058 19.086068 270)
			(size 0.4318 0.4318)
			(layers "F.Cu" "F.Mask" "F.Paste")
			(net "GND")
		)
		(pad "DW66" smd circle
			(at 17.07769 19.086068 270)
			(size 0.4318 0.4318)
			(layers "F.Cu" "F.Mask" "F.Paste")
			(net "GND")
		)
		(pad "DW68" smd circle
			(at 18.705576 19.086068 270)
			(size 0.4318 0.4318)
			(layers "F.Cu" "F.Mask" "F.Paste")
			(net "GND")
		)
		(pad "DW70" smd circle
			(at 20.333462 19.086068 270)
			(size 0.4318 0.4318)
			(layers "F.Cu" "F.Mask" "F.Paste")
			(net "GND")
		)
		(pad "DW72" smd circle
			(at 21.961094 19.086068 270)
			(size 0.4318 0.4318)
			(layers "F.Cu" "F.Mask" "F.Paste")
			(net "GND")
		)
		(pad "DW74" smd circle
			(at 23.58898 19.086068 270)
			(size 0.4318 0.4318)
			(layers "F.Cu" "F.Mask" "F.Paste")
			(net "GND")
		)
		(pad "DW76" smd circle
			(at 25.216612 19.086068 270)
			(size 0.4318 0.4318)
			(layers "F.Cu" "F.Mask" "F.Paste")
			(net "GND")
		)
		(pad "DW78" smd circle
			(at 26.844498 19.086068 270)
			(size 0.4318 0.4318)
			(layers "F.Cu" "F.Mask" "F.Paste")
			(net "M_H_CPU0_SA_DQ<2>")
		)
		(pad "DW80" smd circle
			(at 28.472384 19.086068 270)
			(size 0.4318 0.4318)
			(layers "F.Cu" "F.Mask" "F.Paste")
			(net "GND")
		)
		(pad "DW82" smd circle
			(at 30.100016 19.086068 270)
			(size 0.4318 0.4318)
			(layers "F.Cu" "F.Mask" "F.Paste")
			(net "GND")
		)
		(pad "DW84" smd circle
			(at 31.727902 19.086068 270)
			(size 0.4318 0.4318)
			(layers "F.Cu" "F.Mask" "F.Paste")
			(net "GND")
		)
		(pad "DW86" smd circle
			(at 33.355534 19.086068 270)
			(size 0.4318 0.4318)
			(layers "F.Cu" "F.Mask" "F.Paste")
			(net "P5E_CPU0_PE3_TX_DP<3>")
		)
		(pad "DW88" smd circle
			(at 34.98342 19.086068 270)
			(size 0.4318 0.4318)
			(layers "F.Cu" "F.Mask" "F.Paste")
			(net "GND")
		)
	)
)
